(kicad_pcb
	(version 20260206)
	(generator "pcbnew")
	(generator_version "10.0")
	(general
		(thickness 1.6)
		(legacy_teardrops no)
	)
	(paper "A4")
	(title_block
		(title "peb — Lightning_PEB_BRD.brd")
		(comment 1 "Lightning (Wiwynn / Facebook NVMe JBOF) / footprints 886-891 of 2563")
	)
	(layers
		(0 "F.Cu" signal "TOP")
		(4 "In1.Cu" signal "L2GND")
		(6 "In2.Cu" signal "L3")
		(8 "In3.Cu" signal "L4VCC")
		(10 "In4.Cu" signal "L5VCC")
		(12 "In5.Cu" signal "L6")
		(14 "In6.Cu" signal "L7GND")
		(2 "B.Cu" signal "BOTTOM")
		(9 "F.Adhes" user "F.Adhesive")
		(11 "B.Adhes" user "B.Adhesive")
		(13 "F.Paste" user "Package Geometry/Pastemask Top")
		(15 "B.Paste" user "Package Geometry/Pastemask Bottom")
		(5 "F.SilkS" user "Ref Des/Silkscreen Top")
		(7 "B.SilkS" user "Ref Des/Silkscreen Bottom")
		(1 "F.Mask" user "Board Geometry/Soldermask Top")
		(3 "B.Mask" user "Board Geometry/Soldermask Bottom")
		(17 "Dwgs.User" user "User.Drawings")
		(19 "Cmts.User" user "User.Comments")
		(21 "Eco1.User" user "User.Eco1")
		(23 "Eco2.User" user "User.Eco2")
		(25 "Edge.Cuts" user "Board Geometry/Outline")
		(27 "Margin" user)
		(31 "F.CrtYd" user "Package Geometry/Place Bound Top")
		(29 "B.CrtYd" user "Package Geometry/Place Bound Bottom")
		(35 "F.Fab" user "Ref Des/Assembly Top")
		(33 "B.Fab" user "Ref Des/Assembly Bottom")
	)
	(footprint ""
		(layer "F.Cu")
		(at 128.9558 -43.1292 180)
		(property "Reference" "R623"
			(at 0 0 180)
			(layer "F.SilkS")
			(hide yes)
			(effects
				(font
					(size 1.27 1.27)
				)
			)
		)
		(property "Value" "0R2J-2-GP"
			(at 0.064008 -3.993896 180)
			(unlocked yes)
			(layer "F.Fab")
			(hide yes)
			(effects
				(font
					(size 1.016 1.016)
					(thickness 0.1524)
				)
			)
		)
		(property "Device Type" "R402H16"
			(at 0.064008 -5.517896 180)
			(unlocked yes)
			(layer "F.Fab")
			(hide yes)
			(effects
				(font
					(size 1.016 1.016)
					(thickness 0.1524)
				)
			)
		)
		(duplicate_pad_numbers_are_jumpers no)
		(fp_line
			(start 0.508 -0.9398)
			(end -0.508 -0.9398)
			(stroke
				(width 0.1524)
				(type default)
			)
			(layer "F.SilkS")
		)
		(fp_line
			(start -0.508 -0.9398)
			(end -0.508 0.9398)
			(stroke
				(width 0.1524)
				(type default)
			)
			(layer "F.SilkS")
		)
		(fp_rect
			(start -0.508 0.9398)
			(end 0.508 -0.9398)
			(stroke
				(width 0)
				(type default)
			)
			(fill no)
			(layer "F.CrtYd")
		)
		(fp_rect
			(start -0.508 0.9398)
			(end 0.508 -0.9398)
			(stroke
				(width 0)
				(type default)
			)
			(fill no)
			(layer "F.Fab")
		)
		(pad "1" smd custom
			(at 0 -0.4445 180)
			(size 0.1397 0.1397)
			(layers "F.Cu" "F.Mask" "F.Paste")
			(net "UPLINK4_R")
			(options
				(clearance outline)
				(anchor circle)
			)
			(primitives
				(gr_poly
					(pts
						(arc
							(start -0.1778 -0.2794)
							(mid -0.249642 -0.249642)
							(end -0.2794 -0.1778)
						)
						(arc
							(start -0.2794 0.1778)
							(mid -0.249642 0.249642)
							(end -0.1778 0.2794)
						)
						(arc
							(start 0.1778 0.2794)
							(mid 0.249642 0.249642)
							(end 0.2794 0.1778)
						)
						(arc
							(start 0.2794 -0.1778)
							(mid 0.249642 -0.249642)
							(end 0.1778 -0.2794)
						)
					)
					(width 0)
					(fill yes)
				)
			)
		)
		(pad "2" smd custom
			(at 0 0.4445 180)
			(size 0.1397 0.1397)
			(layers "F.Cu" "F.Mask" "F.Paste")
			(net "UPLINK4")
			(options
				(clearance outline)
				(anchor circle)
			)
			(primitives
				(gr_poly
					(pts
						(arc
							(start -0.1778 -0.2794)
							(mid -0.249642 -0.249642)
							(end -0.2794 -0.1778)
						)
						(arc
							(start -0.2794 0.1778)
							(mid -0.249642 0.249642)
							(end -0.1778 0.2794)
						)
						(arc
							(start 0.1778 0.2794)
							(mid 0.249642 0.249642)
							(end 0.2794 0.1778)
						)
						(arc
							(start 0.2794 -0.1778)
							(mid 0.249642 -0.249642)
							(end 0.1778 -0.2794)
						)
					)
					(width 0)
					(fill yes)
				)
			)
		)
	)
	(footprint ""
		(layer "F.Cu")
		(at 9.779 -118.364 90)
		(property "Reference" "R294"
			(at 0 0 90)
			(layer "F.SilkS")
			(hide yes)
			(effects
				(font
					(size 1.27 1.27)
				)
			)
		)
		(property "Value" "4K7R2F-GP"
			(at 0.064008 -3.993896 90)
			(unlocked yes)
			(layer "F.Fab")
			(hide yes)
			(effects
				(font
					(size 1.016 1.016)
					(thickness 0.1524)
				)
			)
		)
		(property "Device Type" "R402H16"
			(at 0.064008 -5.517896 90)
			(unlocked yes)
			(layer "F.Fab")
			(hide yes)
			(effects
				(font
					(size 1.016 1.016)
					(thickness 0.1524)
				)
			)
		)
		(duplicate_pad_numbers_are_jumpers no)
		(fp_line
			(start 0.508 -0.9398)
			(end -0.508 -0.9398)
			(stroke
				(width 0.1524)
				(type default)
			)
			(layer "F.SilkS")
		)
		(fp_line
			(start -0.508 -0.9398)
			(end -0.508 0.9398)
			(stroke
				(width 0.1524)
				(type default)
			)
			(layer "F.SilkS")
		)
		(fp_rect
			(start -0.508 0.9398)
			(end 0.508 -0.9398)
			(stroke
				(width 0)
				(type default)
			)
			(fill no)
			(layer "F.CrtYd")
		)
		(fp_rect
			(start -0.508 0.9398)
			(end 0.508 -0.9398)
			(stroke
				(width 0)
				(type default)
			)
			(fill no)
			(layer "F.Fab")
		)
		(pad "1" smd custom
			(at 0 -0.4445 90)
			(size 0.1397 0.1397)
			(layers "F.Cu" "F.Mask" "F.Paste")
			(net "P3V3_STBY")
			(options
				(clearance outline)
				(anchor circle)
			)
			(primitives
				(gr_poly
					(pts
						(arc
							(start -0.1778 -0.2794)
							(mid -0.249642 -0.249642)
							(end -0.2794 -0.1778)
						)
						(arc
							(start -0.2794 0.1778)
							(mid -0.249642 0.249642)
							(end -0.1778 0.2794)
						)
						(arc
							(start 0.1778 0.2794)
							(mid 0.249642 0.249642)
							(end 0.2794 0.1778)
						)
						(arc
							(start 0.2794 -0.1778)
							(mid 0.249642 -0.249642)
							(end 0.1778 -0.2794)
						)
					)
					(width 0)
					(fill yes)
				)
			)
		)
		(pad "2" smd custom
			(at 0 0.4445 90)
			(size 0.1397 0.1397)
			(layers "F.Cu" "F.Mask" "F.Paste")
			(net "I2C1_LS_G1")
			(options
				(clearance outline)
				(anchor circle)
			)
			(primitives
				(gr_poly
					(pts
						(arc
							(start -0.1778 -0.2794)
							(mid -0.249642 -0.249642)
							(end -0.2794 -0.1778)
						)
						(arc
							(start -0.2794 0.1778)
							(mid -0.249642 0.249642)
							(end -0.1778 0.2794)
						)
						(arc
							(start 0.1778 0.2794)
							(mid 0.249642 0.249642)
							(end 0.2794 0.1778)
						)
						(arc
							(start 0.2794 -0.1778)
							(mid 0.249642 -0.249642)
							(end 0.1778 -0.2794)
						)
					)
					(width 0)
					(fill yes)
				)
			)
		)
	)
	(footprint ""
		(layer "F.Cu")
		(at 117.5258 -97.1042 180)
		(property "Reference" "R430"
			(at 0 0 180)
			(layer "F.SilkS")
			(hide yes)
			(effects
				(font
					(size 1.27 1.27)
				)
			)
		)
		(property "Value" "10KR2F-2-GP"
			(at 0.064008 -3.993896 180)
			(unlocked yes)
			(layer "F.Fab")
			(hide yes)
			(effects
				(font
					(size 1.016 1.016)
					(thickness 0.1524)
				)
			)
		)
		(property "Device Type" "R402H16"
			(at 0.064008 -5.517896 180)
			(unlocked yes)
			(layer "F.Fab")
			(hide yes)
			(effects
				(font
					(size 1.016 1.016)
					(thickness 0.1524)
				)
			)
		)
		(duplicate_pad_numbers_are_jumpers no)
		(fp_line
			(start 0.508 -0.9398)
			(end -0.508 -0.9398)
			(stroke
				(width 0.1524)
				(type default)
			)
			(layer "F.SilkS")
		)
		(fp_line
			(start -0.508 -0.9398)
			(end -0.508 0.9398)
			(stroke
				(width 0.1524)
				(type default)
			)
			(layer "F.SilkS")
		)
		(fp_rect
			(start -0.508 0.9398)
			(end 0.508 -0.9398)
			(stroke
				(width 0)
				(type default)
			)
			(fill no)
			(layer "F.CrtYd")
		)
		(fp_rect
			(start -0.508 0.9398)
			(end 0.508 -0.9398)
			(stroke
				(width 0)
				(type default)
			)
			(fill no)
			(layer "F.Fab")
		)
		(pad "1" smd custom
			(at 0 -0.4445 180)
			(size 0.1397 0.1397)
			(layers "F.Cu" "F.Mask" "F.Paste")
			(net "I2C10_BUF_READY")
			(options
				(clearance outline)
				(anchor circle)
			)
			(primitives
				(gr_poly
					(pts
						(arc
							(start -0.1778 -0.2794)
							(mid -0.249642 -0.249642)
							(end -0.2794 -0.1778)
						)
						(arc
							(start -0.2794 0.1778)
							(mid -0.249642 0.249642)
							(end -0.1778 0.2794)
						)
						(arc
							(start 0.1778 0.2794)
							(mid 0.249642 0.249642)
							(end 0.2794 0.1778)
						)
						(arc
							(start 0.2794 -0.1778)
							(mid 0.249642 -0.249642)
							(end 0.1778 -0.2794)
						)
					)
					(width 0)
					(fill yes)
				)
			)
		)
		(pad "2" smd custom
			(at 0 0.4445 180)
			(size 0.1397 0.1397)
			(layers "F.Cu" "F.Mask" "F.Paste")
			(net "P3V3_STBY")
			(options
				(clearance outline)
				(anchor circle)
			)
			(primitives
				(gr_poly
					(pts
						(arc
							(start -0.1778 -0.2794)
							(mid -0.249642 -0.249642)
							(end -0.2794 -0.1778)
						)
						(arc
							(start -0.2794 0.1778)
							(mid -0.249642 0.249642)
							(end -0.1778 0.2794)
						)
						(arc
							(start 0.1778 0.2794)
							(mid 0.249642 0.249642)
							(end 0.2794 0.1778)
						)
						(arc
							(start 0.2794 -0.1778)
							(mid 0.249642 -0.249642)
							(end 0.1778 -0.2794)
						)
					)
					(width 0)
					(fill yes)
				)
			)
		)
	)
	(footprint ""
		(layer "F.Cu")
		(at 35.2806 -186.0042 -90)
		(property "Reference" "R966"
			(at 0 0 270)
			(layer "F.SilkS")
			(hide yes)
			(effects
				(font
					(size 1.27 1.27)
				)
			)
		)
		(property "Value" "0R2J-2-GP"
			(at 0.064008 -3.993896 270)
			(unlocked yes)
			(layer "F.Fab")
			(hide yes)
			(effects
				(font
					(size 1.016 1.016)
					(thickness 0.1524)
				)
			)
		)
		(property "Device Type" "R402H16"
			(at 0.064008 -5.517896 270)
			(unlocked yes)
			(layer "F.Fab")
			(hide yes)
			(effects
				(font
					(size 1.016 1.016)
					(thickness 0.1524)
				)
			)
		)
		(duplicate_pad_numbers_are_jumpers no)
		(fp_line
			(start -0.508 -0.9398)
			(end -0.508 0.9398)
			(stroke
				(width 0.1524)
				(type default)
			)
			(layer "F.SilkS")
		)
		(fp_line
			(start 0.508 -0.9398)
			(end -0.508 -0.9398)
			(stroke
				(width 0.1524)
				(type default)
			)
			(layer "F.SilkS")
		)
		(fp_rect
			(start -0.508 0.9398)
			(end 0.508 -0.9398)
			(stroke
				(width 0)
				(type default)
			)
			(fill no)
			(layer "F.CrtYd")
		)
		(fp_rect
			(start -0.508 0.9398)
			(end 0.508 -0.9398)
			(stroke
				(width 0)
				(type default)
			)
			(fill no)
			(layer "F.Fab")
		)
		(pad "1" smd custom
			(at 0 -0.4445 270)
			(size 0.1397 0.1397)
			(layers "F.Cu" "F.Mask" "F.Paste")
			(net "BMC_I2C5_D_PEB_DEVICE_SCL")
			(options
				(clearance outline)
				(anchor circle)
			)
			(primitives
				(gr_poly
					(pts
						(arc
							(start -0.1778 -0.2794)
							(mid -0.249642 -0.249642)
							(end -0.2794 -0.1778)
						)
						(arc
							(start -0.2794 0.1778)
							(mid -0.249642 0.249642)
							(end -0.1778 0.2794)
						)
						(arc
							(start 0.1778 0.2794)
							(mid 0.249642 0.249642)
							(end 0.2794 0.1778)
						)
						(arc
							(start 0.2794 -0.1778)
							(mid 0.249642 -0.249642)
							(end 0.1778 -0.2794)
						)
					)
					(width 0)
					(fill yes)
				)
			)
		)
		(pad "2" smd custom
			(at 0 0.4445 270)
			(size 0.1397 0.1397)
			(layers "F.Cu" "F.Mask" "F.Paste")
			(net "BUF_I2C5_SCL_R")
			(options
				(clearance outline)
				(anchor circle)
			)
			(primitives
				(gr_poly
					(pts
						(arc
							(start -0.1778 -0.2794)
							(mid -0.249642 -0.249642)
							(end -0.2794 -0.1778)
						)
						(arc
							(start -0.2794 0.1778)
							(mid -0.249642 0.249642)
							(end -0.1778 0.2794)
						)
						(arc
							(start 0.1778 0.2794)
							(mid 0.249642 0.249642)
							(end 0.2794 0.1778)
						)
						(arc
							(start 0.2794 -0.1778)
							(mid 0.249642 -0.249642)
							(end 0.1778 -0.2794)
						)
					)
					(width 0)
					(fill yes)
				)
			)
		)
	)
	(footprint ""
		(layer "F.Cu")
		(at 38.608 -51.943 90)
		(property "Reference" "TC17"
			(at 0 0 90)
			(layer "F.SilkS")
			(hide yes)
			(effects
				(font
					(size 1.27 1.27)
				)
			)
		)
		(property "Value" "ST150U6D3VDM-28-GP"
			(at 0 -9.6012 90)
			(unlocked yes)
			(layer "F.Fab")
			(hide yes)
			(effects
				(font
					(size 1.016 1.016)
					(thickness 0.1524)
				)
			)
		)
		(property "Device Type" "CT7343H83"
			(at 0 -11.1252 90)
			(unlocked yes)
			(layer "F.Fab")
			(hide yes)
			(effects
				(font
					(size 1.016 1.016)
					(thickness 0.1524)
				)
			)
		)
		(duplicate_pad_numbers_are_jumpers no)
		(fp_line
			(start 2.286 -4.8768)
			(end -2.286 -4.8768)
			(stroke
				(width 0.1524)
				(type default)
			)
			(layer "F.SilkS")
		)
		(fp_line
			(start -2.286 -4.8768)
			(end -2.286 -2.032)
			(stroke
				(width 0.1524)
				(type default)
			)
			(layer "F.SilkS")
		)
		(fp_line
			(start 2.1082 -4.699)
			(end -2.1082 -4.699)
			(stroke
				(width 0.508)
				(type default)
			)
			(layer "F.SilkS")
		)
		(fp_line
			(start 2.286 -2.032)
			(end 2.286 -4.8768)
			(stroke
				(width 0.1524)
				(type default)
			)
			(layer "F.SilkS")
		)
		(fp_line
			(start 2.286 2.032)
			(end 2.286 4.8768)
			(stroke
				(width 0.1524)
				(type default)
			)
			(layer "F.SilkS")
		)
		(fp_line
			(start 2.286 4.8768)
			(end -2.286 4.8768)
			(stroke
				(width 0.1524)
				(type default)
			)
			(layer "F.SilkS")
		)
		(fp_line
			(start -2.286 4.8768)
			(end -2.286 2.032)
			(stroke
				(width 0.1524)
				(type default)
			)
			(layer "F.SilkS")
		)
		(fp_rect
			(start -2.1463 3.6449)
			(end 2.1463 -3.6449)
			(stroke
				(width 0)
				(type default)
			)
			(fill no)
			(layer "F.CrtYd")
		)
		(fp_poly
			(pts
				(xy -2.54 4.953) (xy -2.54 4.2926) (xy -3.81 4.2926) (xy -3.81 -4.2926) (xy -2.54 -4.2926) (xy -2.54 -4.953)
				(xy 2.54 -4.953) (xy 2.54 -4.2926) (xy 3.81 -4.2926) (xy 3.81 -1.6256) (xy 2.1463 -1.6256) (xy 2.1463 -3.6449)
				(xy -2.1463 -3.6449) (xy -2.1463 3.6449) (xy 2.1463 3.6449) (xy 2.1463 -1.6129) (xy 3.81 -1.6129)
				(xy 3.81 4.2926) (xy 2.54 4.2926) (xy 2.54 4.953)
			)
			(stroke
				(width 0)
				(type default)
			)
			(fill no)
			(layer "F.CrtYd")
		)
		(fp_rect
			(start 2.54 4.2926)
			(end 3.81 -4.2926)
			(stroke
				(width 0)
				(type default)
			)
			(fill no)
			(layer "F.Fab")
		)
		(fp_rect
			(start -3.81 4.2926)
			(end -2.54 -4.2926)
			(stroke
				(width 0)
				(type default)
			)
			(fill no)
			(layer "F.Fab")
		)
		(fp_rect
			(start -2.54 4.953)
			(end 2.54 -4.953)
			(stroke
				(width 0)
				(type default)
			)
			(fill no)
			(layer "F.Fab")
		)
		(pad "1" smd rect
			(at 0 -3.1496 90)
			(size 2.413 2.286)
			(layers "F.Cu" "F.Mask" "F.Paste")
			(net "P5V_USB")
		)
		(pad "2" smd rect
			(at 0 3.1496 90)
			(size 2.413 2.286)
			(layers "F.Cu" "F.Mask" "F.Paste")
			(net "GND")
		)
		(zone
			(layer "F.Cu")
			(hatch none 0.5)
			(connect_pads
				(clearance 0)
			)
			(min_thickness 0.25)
			(keepout
				(tracks allowed)
				(vias not_allowed)
				(pads allowed)
				(copperpour not_allowed)
				(footprints allowed)
			)
			(placement
				(enabled no)
				(sheetname "")
			)
			(fill
				(thermal_gap 0.5)
				(thermal_bridge_width 0.5)
				(island_removal_mode 0)
			)
			(polygon
				(pts
					(xy 36.9189 -53.4543) (xy 34.0106 -53.4543) (xy 34.0106 -50.4317) (xy 36.9062 -50.4317) (xy 37.2364 -50.4317)
					(xy 37.2364 -53.4543)
				)
			)
		)
		(zone
			(layer "F.Cu")
			(hatch none 0.5)
			(connect_pads
				(clearance 0)
			)
			(min_thickness 0.25)
			(keepout
				(tracks allowed)
				(vias not_allowed)
				(pads allowed)
				(copperpour not_allowed)
				(footprints allowed)
			)
			(placement
				(enabled no)
				(sheetname "")
			)
			(fill
				(thermal_gap 0.5)
				(thermal_bridge_width 0.5)
				(island_removal_mode 0)
			)
			(polygon
				(pts
					(xy 43.2054 -50.4317) (xy 43.2054 -53.4543) (xy 40.3098 -53.4543) (xy 39.9796 -53.4543) (xy 39.9796 -50.4317)
					(xy 40.3098 -50.4317)
				)
			)
		)
	)
	(footprint ""
		(layer "F.Cu")
		(at 20.5994 -52.0192 90)
		(property "Reference" "D18"
			(at 0 0 90)
			(layer "F.SilkS")
			(hide yes)
			(effects
				(font
					(size 1.27 1.27)
				)
			)
		)
		(property "Value" "PGB1010603MR-GP"
			(at -0.0254 -2.8956 90)
			(unlocked yes)
			(layer "F.Fab")
			(hide yes)
			(effects
				(font
					(size 1.016 1.016)
					(thickness 0.1524)
				)
			)
		)
		(property "Device Type" "L1608-UH15"
			(at -0.0254 -4.4196 90)
			(unlocked yes)
			(layer "F.Fab")
			(hide yes)
			(effects
				(font
					(size 1.016 1.016)
					(thickness 0.1524)
				)
			)
		)
		(duplicate_pad_numbers_are_jumpers no)
		(fp_line
			(start 0.254 0)
			(end -0.254 0)
			(stroke
				(width 0.2032)
				(type default)
			)
			(layer "F.SilkS")
		)
		(fp_rect
			(start -0.5842 1.3335)
			(end 0.5842 -1.3335)
			(stroke
				(width 0)
				(type default)
			)
			(fill no)
			(layer "F.CrtYd")
		)
		(fp_rect
			(start -0.5842 1.3335)
			(end 0.5842 -1.3335)
			(stroke
				(width 0)
				(type default)
			)
			(fill no)
			(layer "F.Fab")
		)
		(pad "1" smd custom
			(at 0 -0.762 90)
			(size 0.2159 0.2159)
			(layers "F.Cu" "F.Mask" "F.Paste")
			(net "NIC0_MDI0_N2_R")
			(options
				(clearance outline)
				(anchor circle)
			)
			(primitives
				(gr_poly
					(pts
						(arc
							(start -0.3302 -0.4318)
							(mid -0.402042 -0.402042)
							(end -0.4318 -0.3302)
						)
						(arc
							(start -0.4318 0.3302)
							(mid -0.402042 0.402042)
							(end -0.3302 0.4318)
						)
						(arc
							(start 0.3302 0.4318)
							(mid 0.402042 0.402042)
							(end 0.4318 0.3302)
						)
						(arc
							(start 0.4318 -0.3302)
							(mid 0.402042 -0.402042)
							(end 0.3302 -0.4318)
						)
					)
					(width 0)
					(fill yes)
				)
			)
		)
		(pad "2" smd custom
			(at 0 0.762 90)
			(size 0.2159 0.2159)
			(layers "F.Cu" "F.Mask" "F.Paste")
			(net "GND")
			(options
				(clearance outline)
				(anchor circle)
			)
			(primitives
				(gr_poly
					(pts
						(arc
							(start -0.3302 -0.4318)
							(mid -0.402042 -0.402042)
							(end -0.4318 -0.3302)
						)
						(arc
							(start -0.4318 0.3302)
							(mid -0.402042 0.402042)
							(end -0.3302 0.4318)
						)
						(arc
							(start 0.3302 0.4318)
							(mid 0.402042 0.402042)
							(end 0.4318 0.3302)
						)
						(arc
							(start 0.4318 -0.3302)
							(mid 0.402042 -0.402042)
							(end 0.3302 -0.4318)
						)
					)
					(width 0)
					(fill yes)
				)
			)
		)
	)
)
